(kicad_pcb
	(version 20241229)
	(generator "pcbnew")
	(generator_version "9.0")
	(general
		(thickness 1.62)
		(legacy_teardrops no)
	)
	(paper "A3")
	(title_block
		(title "COM Express 7 Baseboard")
		(date "2025-02-04")
		(rev "1.1.2")
		(company "Antmicro Ltd")
		(comment 1 "www.antmicro.com")
		(comment 9 "footprints 617-621 of 802")
	)
	(layers
		(0 "F.Cu" signal)
		(4 "In1.Cu" signal)
		(6 "In2.Cu" signal)
		(8 "In3.Cu" signal)
		(10 "In4.Cu" signal)
		(12 "In5.Cu" signal)
		(14 "In6.Cu" signal)
		(2 "B.Cu" signal)
		(9 "F.Adhes" user "F.Adhesive")
		(11 "B.Adhes" user "B.Adhesive")
		(13 "F.Paste" user)
		(15 "B.Paste" user)
		(5 "F.SilkS" user "F.Silkscreen")
		(7 "B.SilkS" user "B.Silkscreen")
		(1 "F.Mask" user)
		(3 "B.Mask" user)
		(17 "Dwgs.User" user "User.Drawings")
		(19 "Cmts.User" user "User.Comments")
		(21 "Eco1.User" user "User.Eco1")
		(23 "Eco2.User" user "User.Eco2")
		(25 "Edge.Cuts" user)
		(27 "Margin" user)
		(31 "F.CrtYd" user "F.Courtyard")
		(29 "B.CrtYd" user "B.Courtyard")
		(35 "F.Fab" user)
		(33 "B.Fab" user)
	)
	(footprint "antmicro-footprints:R_0603_1608Metric"
		(layer "B.Cu")
		(at 304.7 81.46)
		(descr "Resistor SMD 0603")
		(tags "resistor SMD 0603")
		(property "Reference" "R131"
			(at -1.45 1.55 0)
			(layer "B.SilkS")
			(effects
				(font
					(size 0.7 0.7)
					(thickness 0.15)
				)
				(justify right bottom mirror)
			)
		)
		(property "Value" "R_0R_22.4A_0603"
			(at 0 -1.6 0)
			(layer "B.Fab")
			(effects
				(font
					(size 0.7 0.7)
					(thickness 0.15)
				)
				(justify right bottom mirror)
			)
		)
		(property "Datasheet" "https://fscdn.rohm.com/en/products/databook/datasheet/passive/resistor/chip_resistor/pmr-jpw-e.pdf"
			(at 0 0 0)
			(layer "F.Fab")
			(hide yes)
			(effects
				(font
					(size 1.27 1.27)
					(thickness 0.15)
				)
			)
		)
		(property "Author" "Antmicro"
			(at 0 0 0)
			(layer "B.Fab")
			(hide yes)
			(effects
				(font
					(size 1 1)
					(thickness 0.15)
				)
				(justify mirror)
			)
		)
		(property "License" "Apache-2.0"
			(at 0 0 0)
			(layer "B.Fab")
			(hide yes)
			(effects
				(font
					(size 1 1)
					(thickness 0.15)
				)
				(justify mirror)
			)
		)
		(property "MPN" "PMR03EZPJ000"
			(at 0 0 0)
			(layer "B.Fab")
			(hide yes)
			(effects
				(font
					(size 1 1)
					(thickness 0.15)
				)
				(justify mirror)
			)
		)
		(property "Manufacturer" "ROHM Semiconductor"
			(at 0 0 0)
			(layer "B.Fab")
			(hide yes)
			(effects
				(font
					(size 1 1)
					(thickness 0.15)
				)
				(justify mirror)
			)
		)
		(property "Max. Curr." "22.4A"
			(at 0 0 0)
			(layer "B.Fab")
			(hide yes)
			(effects
				(font
					(size 1 1)
					(thickness 0.15)
				)
				(justify mirror)
			)
		)
		(property "Public" "False"
			(at 0 0 0)
			(layer "B.Fab")
			(hide yes)
			(effects
				(font
					(size 1 1)
					(thickness 0.15)
				)
				(justify mirror)
			)
		)
		(property "Tolerance" "template_tolerance"
			(at 0 0 0)
			(layer "B.Fab")
			(hide yes)
			(effects
				(font
					(size 1 1)
					(thickness 0.15)
				)
				(justify mirror)
			)
		)
		(property "Val" "0R"
			(at 0 0 0)
			(layer "B.Fab")
			(hide yes)
			(effects
				(font
					(size 1 1)
					(thickness 0.15)
				)
				(justify mirror)
			)
		)
		(sheetname "M.2 key M #2")
		(sheetfile "m2keym.kicad_sch")
		(attr smd)
		(fp_line
			(start 0.15 -0.4)
			(end -0.15 -0.4)
			(stroke
				(width 0.15)
				(type solid)
			)
			(layer "B.SilkS")
		)
		(fp_line
			(start 0.15 0.4)
			(end -0.15 0.4)
			(stroke
				(width 0.15)
				(type solid)
			)
			(layer "B.SilkS")
		)
		(fp_rect
			(start -1.25 0.65)
			(end 1.25 -0.65)
			(stroke
				(width 0.05)
				(type solid)
			)
			(fill no)
			(layer "B.CrtYd")
		)
		(fp_rect
			(start -0.8 0.4)
			(end 0.8 -0.4)
			(stroke
				(width 0.15)
				(type solid)
			)
			(fill no)
			(layer "B.Fab")
		)
		(pad "1" smd roundrect
			(at -0.7 0)
			(size 0.8 1)
			(layers "B.Cu" "B.Mask" "B.Paste")
			(roundrect_rratio 0.2)
			(net 970 "/M.2 key M #2/M2_3V3")
			(pintype "passive")
			(teardrops
				(best_length_ratio 0.2)
				(max_length 1)
				(best_width_ratio 0.9)
				(max_width 2)
				(curved_edges yes)
				(filter_ratio 0.9)
				(enabled yes)
				(allow_two_segments yes)
				(prefer_zone_connections yes)
			)
		)
		(pad "2" smd roundrect
			(at 0.7 0)
			(size 0.8 1)
			(layers "B.Cu" "B.Mask" "B.Paste")
			(roundrect_rratio 0.2)
			(net 2 "+3V3")
			(pintype "passive")
			(teardrops
				(best_length_ratio 0.2)
				(max_length 1)
				(best_width_ratio 0.9)
				(max_width 2)
				(curved_edges yes)
				(filter_ratio 0.9)
				(enabled yes)
				(allow_two_segments yes)
				(prefer_zone_connections yes)
			)
		)
	)
	(footprint "antmicro-footprints:R_0402_1005Metric"
		(layer "B.Cu")
		(at 147.05 169.16 -90)
		(descr "Resistor SMD 0402")
		(tags "resistor SMD 0402")
		(property "Reference" "R58"
			(at -3.9 13.5 90)
			(layer "B.SilkS")
			(effects
				(font
					(size 0.7 0.7)
					(thickness 0.15)
				)
				(justify left bottom mirror)
			)
		)
		(property "Value" "R_0R_0402"
			(at -1.011843 -1.772047 90)
			(layer "B.Fab")
			(effects
				(font
					(size 0.7 0.7)
					(thickness 0.15)
				)
				(justify left bottom mirror)
			)
		)
		(property "Datasheet" "https://industrial.panasonic.com/cdbs/www-data/pdf/RDA0000/AOA0000C301.pdf"
			(at 0 0 270)
			(layer "F.Fab")
			(hide yes)
			(effects
				(font
					(size 1.27 1.27)
					(thickness 0.15)
				)
			)
		)
		(property "Author" "Antmicro"
			(at -22.11 316.21 0)
			(layer "B.Fab")
			(hide yes)
			(effects
				(font
					(size 1 1)
					(thickness 0.15)
				)
				(justify mirror)
			)
		)
		(property "Current" "1A"
			(at -22.11 316.21 0)
			(layer "B.Fab")
			(hide yes)
			(effects
				(font
					(size 1 1)
					(thickness 0.15)
				)
				(justify mirror)
			)
		)
		(property "License" "Apache-2.0"
			(at -22.11 316.21 0)
			(layer "B.Fab")
			(hide yes)
			(effects
				(font
					(size 1 1)
					(thickness 0.15)
				)
				(justify mirror)
			)
		)
		(property "MPN" "ERJ2GE0R00X"
			(at -22.11 316.21 0)
			(layer "B.Fab")
			(hide yes)
			(effects
				(font
					(size 1 1)
					(thickness 0.15)
				)
				(justify mirror)
			)
		)
		(property "Manufacturer" "Panasonic"
			(at -22.11 316.21 0)
			(layer "B.Fab")
			(hide yes)
			(effects
				(font
					(size 1 1)
					(thickness 0.15)
				)
				(justify mirror)
			)
		)
		(property "Public" "False"
			(at -22.11 316.21 0)
			(layer "B.Fab")
			(hide yes)
			(effects
				(font
					(size 1 1)
					(thickness 0.15)
				)
				(justify mirror)
			)
		)
		(property "Tolerance" ""
			(at -22.11 316.21 0)
			(layer "B.Fab")
			(hide yes)
			(effects
				(font
					(size 1 1)
					(thickness 0.15)
				)
				(justify mirror)
			)
		)
		(property "Val" "0R"
			(at -22.11 316.21 0)
			(layer "B.Fab")
			(hide yes)
			(effects
				(font
					(size 1 1)
					(thickness 0.15)
				)
				(justify mirror)
			)
		)
		(sheetname "2xSFP+")
		(sheetfile "2xSFP+.kicad_sch")
		(attr smd)
		(fp_rect
			(start -0.925 0.47)
			(end 0.925 -0.47)
			(stroke
				(width 0.05)
				(type default)
			)
			(fill no)
			(layer "B.CrtYd")
		)
		(fp_rect
			(start -0.5 0.25)
			(end 0.5 -0.25)
			(stroke
				(width 0.15)
				(type solid)
			)
			(fill no)
			(layer "B.Fab")
		)
		(pad "1" smd roundrect
			(at -0.48 0 270)
			(size 0.59 0.64)
			(layers "B.Cu" "B.Mask" "B.Paste")
			(roundrect_rratio 0.25)
			(net 169 "Net-(J2A-RS1)")
			(pintype "passive")
			(teardrops
				(best_length_ratio 0.2)
				(max_length 1)
				(best_width_ratio 0.9)
				(max_width 2)
				(curved_edges yes)
				(filter_ratio 0.9)
				(enabled yes)
				(allow_two_segments yes)
				(prefer_zone_connections yes)
			)
		)
		(pad "2" smd roundrect
			(at 0.48 0 270)
			(size 0.59 0.64)
			(layers "B.Cu" "B.Mask" "B.Paste")
			(roundrect_rratio 0.25)
			(net 1 "GND")
			(pintype "passive")
			(teardrops
				(best_length_ratio 0.2)
				(max_length 1)
				(best_width_ratio 0.9)
				(max_width 2)
				(curved_edges yes)
				(filter_ratio 0.9)
				(enabled yes)
				(allow_two_segments yes)
				(prefer_zone_connections yes)
			)
		)
	)
	(footprint "antmicro-footprints:C_0402_1005Metric"
		(layer "B.Cu")
		(at 242.620708 78.135)
		(descr "Capacitor SMD 0402")
		(tags "capacitor SMD 0402")
		(property "Reference" "C85"
			(at -1.1 1.375 0)
			(layer "B.SilkS")
			(effects
				(font
					(size 0.7 0.7)
					(thickness 0.15)
				)
				(justify right bottom mirror)
			)
		)
		(property "Value" "C_100n_0402"
			(at -1.022927 -2.155213 0)
			(layer "B.Fab")
			(effects
				(font
					(size 0.7 0.7)
					(thickness 0.15)
				)
				(justify right bottom mirror)
			)
		)
		(property "Datasheet" "https://www.murata.com/products/productdetail?partno=GRM155R61H104KE14%23"
			(at 0 0 0)
			(layer "F.Fab")
			(hide yes)
			(effects
				(font
					(size 1.27 1.27)
					(thickness 0.15)
				)
			)
		)
		(property "Author" "Antmicro"
			(at 0 0 0)
			(layer "B.Fab")
			(hide yes)
			(effects
				(font
					(size 1 1)
					(thickness 0.15)
				)
				(justify mirror)
			)
		)
		(property "Dielectric" "X5R"
			(at 0 0 0)
			(layer "B.Fab")
			(hide yes)
			(effects
				(font
					(size 1 1)
					(thickness 0.15)
				)
				(justify mirror)
			)
		)
		(property "License" "Apache-2.0"
			(at 0 0 0)
			(layer "B.Fab")
			(hide yes)
			(effects
				(font
					(size 1 1)
					(thickness 0.15)
				)
				(justify mirror)
			)
		)
		(property "MPN" "GRM155R61H104KE14D"
			(at 0 0 0)
			(layer "B.Fab")
			(hide yes)
			(effects
				(font
					(size 1 1)
					(thickness 0.15)
				)
				(justify mirror)
			)
		)
		(property "Manufacturer" "Murata"
			(at 0 0 0)
			(layer "B.Fab")
			(hide yes)
			(effects
				(font
					(size 1 1)
					(thickness 0.15)
				)
				(justify mirror)
			)
		)
		(property "Public" "False"
			(at 0 0 0)
			(layer "B.Fab")
			(hide yes)
			(effects
				(font
					(size 1 1)
					(thickness 0.15)
				)
				(justify mirror)
			)
		)
		(property "Val" "100n"
			(at 0 0 0)
			(layer "B.Fab")
			(hide yes)
			(effects
				(font
					(size 1 1)
					(thickness 0.15)
				)
				(justify mirror)
			)
		)
		(property "Voltage" "50V"
			(at 0 0 0)
			(layer "B.Fab")
			(hide yes)
			(effects
				(font
					(size 1 1)
					(thickness 0.15)
				)
				(justify mirror)
			)
		)
		(sheetname "Misc")
		(sheetfile "misc.kicad_sch")
		(attr smd)
		(fp_rect
			(start -0.925 0.47)
			(end 0.925 -0.47)
			(stroke
				(width 0.05)
				(type default)
			)
			(fill no)
			(layer "B.CrtYd")
		)
		(fp_line
			(start -0.494 -0.248)
			(end 0.504 -0.248)
			(stroke
				(width 0.15)
				(type solid)
			)
			(layer "B.Fab")
		)
		(fp_line
			(start -0.494 0.25)
			(end -0.494 -0.248)
			(stroke
				(width 0.15)
				(type solid)
			)
			(layer "B.Fab")
		)
		(fp_line
			(start 0.504 -0.248)
			(end 0.504 0.25)
			(stroke
				(width 0.15)
				(type solid)
			)
			(layer "B.Fab")
		)
		(fp_line
			(start 0.504 0.25)
			(end -0.494 0.25)
			(stroke
				(width 0.15)
				(type solid)
			)
			(layer "B.Fab")
		)
		(pad "1" smd roundrect
			(at -0.48 0)
			(size 0.59 0.64)
			(layers "B.Cu" "B.Mask" "B.Paste")
			(roundrect_rratio 0.25)
			(net 1 "GND")
			(pintype "passive")
			(teardrops
				(best_length_ratio 0.2)
				(max_length 1)
				(best_width_ratio 0.9)
				(max_width 2)
				(curved_edges yes)
				(filter_ratio 0.9)
				(enabled yes)
				(allow_two_segments yes)
				(prefer_zone_connections yes)
			)
		)
		(pad "2" smd roundrect
			(at 0.48 0)
			(size 0.59 0.64)
			(layers "B.Cu" "B.Mask" "B.Paste")
			(roundrect_rratio 0.25)
			(net 2 "+3V3")
			(pintype "passive")
			(teardrops
				(best_length_ratio 0.2)
				(max_length 1)
				(best_width_ratio 0.9)
				(max_width 2)
				(curved_edges yes)
				(filter_ratio 0.9)
				(enabled yes)
				(allow_two_segments yes)
				(prefer_zone_connections yes)
			)
		)
	)
	(footprint "antmicro-footprints:C_0402_1005Metric"
		(layer "B.Cu")
		(at 150.45 136.36 -90)
		(descr "Capacitor SMD 0402")
		(tags "capacitor SMD 0402")
		(property "Reference" "C159"
			(at -1.15 0.5 270)
			(layer "B.SilkS")
			(effects
				(font
					(size 0.7 0.7)
					(thickness 0.15)
				)
				(justify left bottom mirror)
			)
		)
		(property "Value" "C_100n_0402"
			(at -1.022927 -2.155213 90)
			(layer "B.Fab")
			(effects
				(font
					(size 0.7 0.7)
					(thickness 0.15)
				)
				(justify left bottom mirror)
			)
		)
		(property "Datasheet" "https://www.murata.com/products/productdetail?partno=GRM155R61H104KE14%23"
			(at 0 0 270)
			(layer "F.Fab")
			(hide yes)
			(effects
				(font
					(size 1.27 1.27)
					(thickness 0.15)
				)
			)
		)
		(property "Author" "Antmicro"
			(at 14.09 286.81 0)
			(layer "B.Fab")
			(hide yes)
			(effects
				(font
					(size 1 1)
					(thickness 0.15)
				)
				(justify mirror)
			)
		)
		(property "Dielectric" "X5R"
			(at 14.09 286.81 0)
			(layer "B.Fab")
			(hide yes)
			(effects
				(font
					(size 1 1)
					(thickness 0.15)
				)
				(justify mirror)
			)
		)
		(property "License" "Apache-2.0"
			(at 14.09 286.81 0)
			(layer "B.Fab")
			(hide yes)
			(effects
				(font
					(size 1 1)
					(thickness 0.15)
				)
				(justify mirror)
			)
		)
		(property "MPN" "GRM155R61H104KE14D"
			(at 14.09 286.81 0)
			(layer "B.Fab")
			(hide yes)
			(effects
				(font
					(size 1 1)
					(thickness 0.15)
				)
				(justify mirror)
			)
		)
		(property "Manufacturer" "Murata"
			(at 14.09 286.81 0)
			(layer "B.Fab")
			(hide yes)
			(effects
				(font
					(size 1 1)
					(thickness 0.15)
				)
				(justify mirror)
			)
		)
		(property "Public" "False"
			(at 14.09 286.81 0)
			(layer "B.Fab")
			(hide yes)
			(effects
				(font
					(size 1 1)
					(thickness 0.15)
				)
				(justify mirror)
			)
		)
		(property "Val" "100n"
			(at 14.09 286.81 0)
			(layer "B.Fab")
			(hide yes)
			(effects
				(font
					(size 1 1)
					(thickness 0.15)
				)
				(justify mirror)
			)
		)
		(property "Voltage" "50V"
			(at 14.09 286.81 0)
			(layer "B.Fab")
			(hide yes)
			(effects
				(font
					(size 1 1)
					(thickness 0.15)
				)
				(justify mirror)
			)
		)
		(sheetname "KR to SFI #1")
		(sheetfile "kr_sfi.kicad_sch")
		(attr smd)
		(fp_rect
			(start -0.925 0.47)
			(end 0.925 -0.47)
			(stroke
				(width 0.05)
				(type default)
			)
			(fill no)
			(layer "B.CrtYd")
		)
		(fp_line
			(start -0.494 0.25)
			(end -0.494 -0.248)
			(stroke
				(width 0.15)
				(type solid)
			)
			(layer "B.Fab")
		)
		(fp_line
			(start 0.504 0.25)
			(end -0.494 0.25)
			(stroke
				(width 0.15)
				(type solid)
			)
			(layer "B.Fab")
		)
		(fp_line
			(start -0.494 -0.248)
			(end 0.504 -0.248)
			(stroke
				(width 0.15)
				(type solid)
			)
			(layer "B.Fab")
		)
		(fp_line
			(start 0.504 -0.248)
			(end 0.504 0.25)
			(stroke
				(width 0.15)
				(type solid)
			)
			(layer "B.Fab")
		)
		(pad "1" smd roundrect
			(at -0.48 0 270)
			(size 0.59 0.64)
			(layers "B.Cu" "B.Mask" "B.Paste")
			(roundrect_rratio 0.25)
			(net 1 "GND")
			(pintype "passive")
			(teardrops
				(best_length_ratio 0.2)
				(max_length 1)
				(best_width_ratio 0.9)
				(max_width 2)
				(curved_edges yes)
				(filter_ratio 0.9)
				(enabled yes)
				(allow_two_segments yes)
				(prefer_zone_connections yes)
			)
		)
		(pad "2" smd roundrect
			(at 0.48 0 270)
			(size 0.59 0.64)
			(layers "B.Cu" "B.Mask" "B.Paste")
			(roundrect_rratio 0.25)
			(net 74 "+1V0")
			(pintype "passive")
			(teardrops
				(best_length_ratio 0.2)
				(max_length 1)
				(best_width_ratio 0.9)
				(max_width 2)
				(curved_edges yes)
				(filter_ratio 0.9)
				(enabled yes)
				(allow_two_segments yes)
				(prefer_zone_connections yes)
			)
		)
	)
	(footprint "antmicro-footprints:C_0402_1005Metric"
		(layer "B.Cu")
		(at 249.725 131.51)
		(descr "Capacitor SMD 0402")
		(tags "capacitor SMD 0402")
		(property "Reference" "C99"
			(at -1.065 1.34 0)
			(layer "B.SilkS")
			(effects
				(font
					(size 0.7 0.7)
					(thickness 0.15)
				)
				(justify right bottom mirror)
			)
		)
		(property "Value" "C_100n_0402"
			(at -1.022927 -2.155213 0)
			(layer "B.Fab")
			(effects
				(font
					(size 0.7 0.7)
					(thickness 0.15)
				)
				(justify right bottom mirror)
			)
		)
		(property "Datasheet" "https://www.murata.com/products/productdetail?partno=GRM155R61H104KE14%23"
			(at 0 0 0)
			(layer "F.Fab")
			(hide yes)
			(effects
				(font
					(size 1.27 1.27)
					(thickness 0.15)
				)
			)
		)
		(property "Author" "Antmicro"
			(at 0 0 0)
			(layer "B.Fab")
			(hide yes)
			(effects
				(font
					(size 1 1)
					(thickness 0.15)
				)
				(justify mirror)
			)
		)
		(property "Dielectric" "X5R"
			(at 0 0 0)
			(layer "B.Fab")
			(hide yes)
			(effects
				(font
					(size 1 1)
					(thickness 0.15)
				)
				(justify mirror)
			)
		)
		(property "License" "Apache-2.0"
			(at 0 0 0)
			(layer "B.Fab")
			(hide yes)
			(effects
				(font
					(size 1 1)
					(thickness 0.15)
				)
				(justify mirror)
			)
		)
		(property "MPN" "GRM155R61H104KE14D"
			(at 0 0 0)
			(layer "B.Fab")
			(hide yes)
			(effects
				(font
					(size 1 1)
					(thickness 0.15)
				)
				(justify mirror)
			)
		)
		(property "Manufacturer" "Murata"
			(at 0 0 0)
			(layer "B.Fab")
			(hide yes)
			(effects
				(font
					(size 1 1)
					(thickness 0.15)
				)
				(justify mirror)
			)
		)
		(property "Public" "False"
			(at 0 0 0)
			(layer "B.Fab")
			(hide yes)
			(effects
				(font
					(size 1 1)
					(thickness 0.15)
				)
				(justify mirror)
			)
		)
		(property "Val" "100n"
			(at 0 0 0)
			(layer "B.Fab")
			(hide yes)
			(effects
				(font
					(size 1 1)
					(thickness 0.15)
				)
				(justify mirror)
			)
		)
		(property "Voltage" "50V"
			(at 0 0 0)
			(layer "B.Fab")
			(hide yes)
			(effects
				(font
					(size 1 1)
					(thickness 0.15)
				)
				(justify mirror)
			)
		)
		(sheetname "Com Express 7 MGMT")
		(sheetfile "com_express_7_mgmt.kicad_sch")
		(attr smd)
		(fp_rect
			(start -0.925 0.47)
			(end 0.925 -0.47)
			(stroke
				(width 0.05)
				(type default)
			)
			(fill no)
			(layer "B.CrtYd")
		)
		(fp_line
			(start -0.494 -0.248)
			(end 0.504 -0.248)
			(stroke
				(width 0.15)
				(type solid)
			)
			(layer "B.Fab")
		)
		(fp_line
			(start -0.494 0.25)
			(end -0.494 -0.248)
			(stroke
				(width 0.15)
				(type solid)
			)
			(layer "B.Fab")
		)
		(fp_line
			(start 0.504 -0.248)
			(end 0.504 0.25)
			(stroke
				(width 0.15)
				(type solid)
			)
			(layer "B.Fab")
		)
		(fp_line
			(start 0.504 0.25)
			(end -0.494 0.25)
			(stroke
				(width 0.15)
				(type solid)
			)
			(layer "B.Fab")
		)
		(pad "1" smd roundrect
			(at -0.48 0)
			(size 0.59 0.64)
			(layers "B.Cu" "B.Mask" "B.Paste")
			(roundrect_rratio 0.25)
			(net 1 "GND")
			(pintype "passive")
			(teardrops
				(best_length_ratio 0.2)
				(max_length 1)
				(best_width_ratio 0.9)
				(max_width 2)
				(curved_edges yes)
				(filter_ratio 0.9)
				(enabled yes)
				(allow_two_segments yes)
				(prefer_zone_connections yes)
			)
		)
		(pad "2" smd roundrect
			(at 0.48 0)
			(size 0.59 0.64)
			(layers "B.Cu" "B.Mask" "B.Paste")
			(roundrect_rratio 0.25)
			(net 73 "+3V3_AON")
			(pintype "passive")
			(teardrops
				(best_length_ratio 0.2)
				(max_length 1)
				(best_width_ratio 0.9)
				(max_width 2)
				(curved_edges yes)
				(filter_ratio 0.9)
				(enabled yes)
				(allow_two_segments yes)
				(prefer_zone_connections yes)
			)
		)
	)
)
